# S9S_MB_2U (Grand Teton) — schematic netlist excerpt (pin names and nets, part order shuffled) for the footprints in the layout excerpt that follows; sources: Cadence DE-HDL packaged netlist, KiCad conversion of 03242023_DA0F0TMBIJ0_F0T_Motherboard_J_brd_V01_OCP.brd

L15  Q_INDUCTOR  BLM18PG300SN1D EMPTY  pkg SMLF  page 250 : \1\ = P3V3_MAX11617_VDD ; \2\ = P3V3_AUX
R1828  Q_RES  10K 1% CHIP  pkg 0402LF  page 183 : A = USB_OC1_REAR_R_N ; B = P3V3_AUX

(kicad_pcb
	(version 20260206)
	(generator "pcbnew")
	(generator_version "10.0")
	(general
		(thickness 1.6)
		(legacy_teardrops no)
	)
	(paper "A4")
	(title_block
		(title "03242023_DA0F0TMBIJ0_F0T_Motherboard_J_brd_V01_OCP.brd")
		(comment 1 "Grand Teton / footprints 2436-2437 of 6105")
	)
	(layers
		(0 "F.Cu" signal "TOP")
		(4 "In1.Cu" signal "GND")
		(6 "In2.Cu" signal "IN1")
		(8 "In3.Cu" signal "GND1")
		(10 "In4.Cu" signal "IN2")
		(12 "In5.Cu" signal "GND2")
		(14 "In6.Cu" signal "IN3")
		(16 "In7.Cu" signal "GND3")
		(18 "In8.Cu" signal "VCC")
		(20 "In9.Cu" signal "VCC1")
		(22 "In10.Cu" signal "GND4")
		(24 "In11.Cu" signal "IN4")
		(26 "In12.Cu" signal "GND5")
		(28 "In13.Cu" signal "IN5")
		(30 "In14.Cu" signal "GND6")
		(32 "In15.Cu" signal "IN6")
		(34 "In16.Cu" signal "GND7")
		(2 "B.Cu" signal "BOTTOM")
		(9 "F.Adhes" user "F.Adhesive")
		(11 "B.Adhes" user "B.Adhesive")
		(13 "F.Paste" user "Package Geometry/Pastemask Top")
		(15 "B.Paste" user "Package Geometry/Pastemask Bottom")
		(5 "F.SilkS" user "Ref Des/Silkscreen Top")
		(7 "B.SilkS" user "Ref Des/Silkscreen Bottom")
		(1 "F.Mask" user "Board Geometry/Soldermask Top")
		(3 "B.Mask" user "Board Geometry/Soldermask Bottom")
		(17 "Dwgs.User" user "User.Drawings")
		(19 "Cmts.User" user "User.Comments")
		(21 "Eco1.User" user "User.Eco1")
		(23 "Eco2.User" user "User.Eco2")
		(25 "Edge.Cuts" user "Board Geometry/Outline")
		(27 "Margin" user)
		(31 "F.CrtYd" user "Package Geometry/Place Bound Top")
		(29 "B.CrtYd" user "Package Geometry/Place Bound Bottom")
		(35 "F.Fab" user "Ref Des/Assembly Top")
		(33 "B.Fab" user "Ref Des/Assembly Bottom")
	)
	(footprint ""
		(layer "F.Cu")
		(at 347.057726 -22.36978 90)
		(property "Reference" "R1828"
			(at 0 0 90)
			(layer "F.SilkS")
			(hide yes)
			(effects
				(font
					(size 1.27 1.27)
				)
			)
		)
		(property "Value" ""
			(at 0 0 90)
			(layer "F.Fab")
			(effects
				(font
					(size 1.27 1.27)
				)
			)
		)
		(duplicate_pad_numbers_are_jumpers no)
		(fp_line
			(start 0.7874 -0.4064)
			(end 0.7874 0.4064)
			(stroke
				(width 0.1524)
				(type default)
			)
			(layer "F.SilkS")
		)
		(fp_line
			(start -0.7874 -0.4064)
			(end 0.7874 -0.4064)
			(stroke
				(width 0.1524)
				(type default)
			)
			(layer "F.SilkS")
		)
		(fp_line
			(start 0.7874 0.4064)
			(end -0.7874 0.4064)
			(stroke
				(width 0.1524)
				(type default)
			)
			(layer "F.SilkS")
		)
		(fp_line
			(start -0.7874 0.4064)
			(end -0.7874 -0.4064)
			(stroke
				(width 0.1524)
				(type default)
			)
			(layer "F.SilkS")
		)
		(fp_line
			(start -0.12065 -0.305054)
			(end -0.12065 -0.2794)
			(stroke
				(width 0.1)
				(type default)
			)
			(layer "F.Fab")
		)
		(fp_line
			(start -0.67945 -0.305054)
			(end -0.12065 -0.305054)
			(stroke
				(width 0.1)
				(type default)
			)
			(layer "F.Fab")
		)
		(fp_line
			(start 0.67945 -0.3048)
			(end 0.67945 0.3048)
			(stroke
				(width 0.1)
				(type default)
			)
			(layer "F.Fab")
		)
		(fp_line
			(start 0.12065 -0.3048)
			(end 0.67945 -0.3048)
			(stroke
				(width 0.1)
				(type default)
			)
			(layer "F.Fab")
		)
		(fp_line
			(start 0.12065 -0.2794)
			(end 0.12065 -0.3048)
			(stroke
				(width 0.1)
				(type default)
			)
			(layer "F.Fab")
		)
		(fp_line
			(start -0.12065 -0.2794)
			(end 0.12065 -0.2794)
			(stroke
				(width 0.1)
				(type default)
			)
			(layer "F.Fab")
		)
		(fp_line
			(start 0.120396 0.2794)
			(end -0.12065 0.2794)
			(stroke
				(width 0.1)
				(type default)
			)
			(layer "F.Fab")
		)
		(fp_line
			(start -0.12065 0.2794)
			(end -0.12065 0.3048)
			(stroke
				(width 0.1)
				(type default)
			)
			(layer "F.Fab")
		)
		(fp_line
			(start 0.67945 0.3048)
			(end 0.120396 0.3048)
			(stroke
				(width 0.1)
				(type default)
			)
			(layer "F.Fab")
		)
		(fp_line
			(start 0.120396 0.3048)
			(end 0.120396 0.2794)
			(stroke
				(width 0.1)
				(type default)
			)
			(layer "F.Fab")
		)
		(fp_line
			(start -0.12065 0.3048)
			(end -0.67945 0.3048)
			(stroke
				(width 0.1)
				(type default)
			)
			(layer "F.Fab")
		)
		(fp_line
			(start -0.67945 0.3048)
			(end -0.67945 -0.305054)
			(stroke
				(width 0.1)
				(type default)
			)
			(layer "F.Fab")
		)
		(pad "1" smd circle
			(at -0.40005 0 90)
			(size 0 0)
			(layers "F.Cu" "F.Mask" "F.Paste")
			(net "USB_OC1_REAR_R_N")
		)
		(pad "2" smd circle
			(at 0.40005 0 90)
			(size 0 0)
			(layers "F.Cu" "F.Mask" "F.Paste")
			(net "P3V3_AUX")
		)
	)
	(footprint ""
		(layer "F.Cu")
		(at 46.676818 -105.874058)
		(property "Reference" "L15"
			(at 0 0 0)
			(layer "F.SilkS")
			(hide yes)
			(effects
				(font
					(size 1.27 1.27)
				)
			)
		)
		(property "Value" ""
			(at 0 0 0)
			(layer "F.Fab")
			(effects
				(font
					(size 1.27 1.27)
				)
			)
		)
		(duplicate_pad_numbers_are_jumpers no)
		(fp_line
			(start -1.27 -0.5842)
			(end 1.27 -0.5842)
			(stroke
				(width 0.1524)
				(type default)
			)
			(layer "F.SilkS")
		)
		(fp_line
			(start -1.27 -0.5588)
			(end -1.27 -0.5842)
			(stroke
				(width 0.1524)
				(type default)
			)
			(layer "F.SilkS")
		)
		(fp_line
			(start -1.27 0.5842)
			(end -1.27 -0.5842)
			(stroke
				(width 0.1524)
				(type default)
			)
			(layer "F.SilkS")
		)
		(fp_line
			(start -0.127 0.5842)
			(end -0.127 -0.5842)
			(stroke
				(width 0.1524)
				(type default)
			)
			(layer "F.SilkS")
		)
		(fp_line
			(start 0.127 0.5842)
			(end 0.127 -0.5842)
			(stroke
				(width 0.1524)
				(type default)
			)
			(layer "F.SilkS")
		)
		(fp_line
			(start 1.27 0.5842)
			(end -1.27 0.5842)
			(stroke
				(width 0.1524)
				(type default)
			)
			(layer "F.SilkS")
		)
		(fp_line
			(start 1.27 0.5842)
			(end 1.27 -0.5842)
			(stroke
				(width 0.1524)
				(type default)
			)
			(layer "F.SilkS")
		)
		(fp_line
			(start -1.194308 -0.406654)
			(end -0.9144 -0.406654)
			(stroke
				(width 0.1)
				(type default)
			)
			(layer "F.Fab")
		)
		(fp_line
			(start -1.194308 0.406654)
			(end -1.194308 -0.406654)
			(stroke
				(width 0.1)
				(type default)
			)
			(layer "F.Fab")
		)
		(fp_line
			(start -0.9144 -0.508)
			(end 0.9144 -0.508)
			(stroke
				(width 0.1)
				(type default)
			)
			(layer "F.Fab")
		)
		(fp_line
			(start -0.9144 -0.406654)
			(end -0.9144 -0.508)
			(stroke
				(width 0.1)
				(type default)
			)
			(layer "F.Fab")
		)
		(fp_line
			(start -0.9144 0.406654)
			(end -1.194308 0.406654)
			(stroke
				(width 0.1)
				(type default)
			)
			(layer "F.Fab")
		)
		(fp_line
			(start -0.9144 0.508)
			(end -0.9144 0.406654)
			(stroke
				(width 0.1)
				(type default)
			)
			(layer "F.Fab")
		)
		(fp_line
			(start 0.9144 -0.508)
			(end 0.9144 -0.406654)
			(stroke
				(width 0.1)
				(type default)
			)
			(layer "F.Fab")
		)
		(fp_line
			(start 0.9144 -0.406654)
			(end 1.1938 -0.406654)
			(stroke
				(width 0.1)
				(type default)
			)
			(layer "F.Fab")
		)
		(fp_line
			(start 0.9144 0.4064)
			(end 0.9144 0.508)
			(stroke
				(width 0.1)
				(type default)
			)
			(layer "F.Fab")
		)
		(fp_line
			(start 0.9144 0.508)
			(end -0.9144 0.508)
			(stroke
				(width 0.1)
				(type default)
			)
			(layer "F.Fab")
		)
		(fp_line
			(start 1.1938 -0.406654)
			(end 1.1938 0.4064)
			(stroke
				(width 0.1)
				(type default)
			)
			(layer "F.Fab")
		)
		(fp_line
			(start 1.1938 0.4064)
			(end 0.9144 0.4064)
			(stroke
				(width 0.1)
				(type default)
			)
			(layer "F.Fab")
		)
		(pad "1" smd rect
			(at -0.7366 0 270)
			(size 0.7112 0.8128)
			(layers "F.Cu" "F.Mask" "F.Paste")
			(net "P3V3_MAX11617_VDD")
		)
		(pad "2" smd rect
			(at 0.7366 0 270)
			(size 0.7112 0.8128)
			(layers "F.Cu" "F.Mask" "F.Paste")
			(net "P3V3_AUX")
		)
	)
)
